(kicad_pcb
	(version 20260206)
	(generator "pcbnew")
	(generator_version "10.0")
	(general
		(thickness 1.6)
		(legacy_teardrops no)
	)
	(paper "A4")
	(title_block
		(title "panther-plus-userver — 13130-1b_20150205.brd")
		(comment 1 "Honey Badger (Wiwynn) / footprints 307-315 of 1509")
	)
	(layers
		(0 "F.Cu" signal "TOP")
		(4 "In1.Cu" signal "L2")
		(6 "In2.Cu" signal "L3")
		(8 "In3.Cu" signal "L4")
		(10 "In4.Cu" signal "L5")
		(12 "In5.Cu" signal "L6")
		(14 "In6.Cu" signal "L7")
		(16 "In7.Cu" signal "L8")
		(18 "In8.Cu" signal "L9")
		(20 "In9.Cu" signal "L10")
		(22 "In10.Cu" signal "L11")
		(2 "B.Cu" signal "BOTTOM")
		(9 "F.Adhes" user "F.Adhesive")
		(11 "B.Adhes" user "B.Adhesive")
		(13 "F.Paste" user "Package Geometry/Pastemask Top")
		(15 "B.Paste" user "Package Geometry/Pastemask Bottom")
		(5 "F.SilkS" user "Ref Des/Silkscreen Top")
		(7 "B.SilkS" user "Ref Des/Silkscreen Bottom")
		(1 "F.Mask" user "Board Geometry/Soldermask Top")
		(3 "B.Mask" user "Board Geometry/Soldermask Bottom")
		(17 "Dwgs.User" user "User.Drawings")
		(19 "Cmts.User" user "User.Comments")
		(21 "Eco1.User" user "User.Eco1")
		(23 "Eco2.User" user "User.Eco2")
		(25 "Edge.Cuts" user "Board Geometry/Outline")
		(27 "Margin" user)
		(31 "F.CrtYd" user "Package Geometry/Place Bound Top")
		(29 "B.CrtYd" user "Package Geometry/Place Bound Bottom")
		(35 "F.Fab" user "Ref Des/Assembly Top")
		(33 "B.Fab" user "Ref Des/Assembly Bottom")
	)
	(footprint ""
		(layer "F.Cu")
		(at 81.788 -65.913 180)
		(property "Reference" "R187"
			(at 0 0 180)
			(layer "F.SilkS")
			(hide yes)
			(effects
				(font
					(size 1.27 1.27)
				)
			)
		)
		(property "Value" "4K7R2F-GP"
			(at 0.064008 -3.993896 180)
			(unlocked yes)
			(layer "F.Fab")
			(hide yes)
			(effects
				(font
					(size 1.016 1.016)
					(thickness 0.1524)
				)
			)
		)
		(property "Device Type" "R402H16"
			(at 0.064008 -5.517896 180)
			(unlocked yes)
			(layer "F.Fab")
			(hide yes)
			(effects
				(font
					(size 1.016 1.016)
					(thickness 0.1524)
				)
			)
		)
		(duplicate_pad_numbers_are_jumpers no)
		(fp_rect
			(start -0.381 0.8382)
			(end 0.381 -0.8382)
			(stroke
				(width 0)
				(type default)
			)
			(fill no)
			(layer "F.CrtYd")
		)
		(fp_rect
			(start -0.381 0.8382)
			(end 0.381 -0.8382)
			(stroke
				(width 0)
				(type default)
			)
			(fill no)
			(layer "F.Fab")
		)
		(pad "1" smd custom
			(at 0 -0.4318 180)
			(size 0.127 0.127)
			(layers "F.Cu" "F.Mask" "F.Paste")
			(net "VOL1_SEN_ADDR0")
			(options
				(clearance outline)
				(anchor circle)
			)
			(primitives
				(gr_poly
					(pts
						(arc
							(start -0.2032 -0.2794)
							(mid -0.239121 -0.264521)
							(end -0.254 -0.2286)
						)
						(arc
							(start -0.254 0.2286)
							(mid -0.239121 0.264521)
							(end -0.2032 0.2794)
						)
						(arc
							(start 0.2032 0.2794)
							(mid 0.239121 0.264521)
							(end 0.254 0.2286)
						)
						(arc
							(start 0.254 -0.2286)
							(mid 0.239121 -0.264521)
							(end 0.2032 -0.2794)
						)
					)
					(width 0)
					(fill yes)
				)
			)
		)
		(pad "2" smd custom
			(at 0 0.4318 180)
			(size 0.127 0.127)
			(layers "F.Cu" "F.Mask" "F.Paste")
			(net "GND")
			(options
				(clearance outline)
				(anchor circle)
			)
			(primitives
				(gr_poly
					(pts
						(arc
							(start -0.2032 -0.2794)
							(mid -0.239121 -0.264521)
							(end -0.254 -0.2286)
						)
						(arc
							(start -0.254 0.2286)
							(mid -0.239121 0.264521)
							(end -0.2032 0.2794)
						)
						(arc
							(start 0.2032 0.2794)
							(mid 0.239121 0.264521)
							(end 0.254 0.2286)
						)
						(arc
							(start 0.254 -0.2286)
							(mid 0.239121 -0.264521)
							(end 0.2032 -0.2794)
						)
					)
					(width 0)
					(fill yes)
				)
			)
		)
	)
	(footprint ""
		(layer "F.Cu")
		(at 191.643 -39.878 180)
		(property "Reference" "PR125"
			(at 0 0 180)
			(layer "F.SilkS")
			(hide yes)
			(effects
				(font
					(size 1.27 1.27)
				)
			)
		)
		(property "Value" "6K04R2F-GP"
			(at 1.7907 -1.1176 180)
			(unlocked yes)
			(layer "F.Fab")
			(hide yes)
			(effects
				(font
					(size 1.016 1.016)
					(thickness 0.1524)
				)
			)
		)
		(property "Device Type" "R402H16"
			(at 1.7907 -2.6416 180)
			(unlocked yes)
			(layer "F.Fab")
			(hide yes)
			(effects
				(font
					(size 1.016 1.016)
					(thickness 0.1524)
				)
			)
		)
		(duplicate_pad_numbers_are_jumpers no)
		(fp_rect
			(start -0.381 0.8382)
			(end 0.381 -0.8382)
			(stroke
				(width 0)
				(type default)
			)
			(fill no)
			(layer "F.CrtYd")
		)
		(fp_rect
			(start -0.381 0.8382)
			(end 0.381 -0.8382)
			(stroke
				(width 0)
				(type default)
			)
			(fill no)
			(layer "F.Fab")
		)
		(pad "1" smd custom
			(at 0 -0.4318 180)
			(size 0.127 0.127)
			(layers "F.Cu" "F.Mask" "F.Paste")
			(net "VR_PVDDR_A_PROG2")
			(options
				(clearance outline)
				(anchor circle)
			)
			(primitives
				(gr_poly
					(pts
						(arc
							(start -0.2032 -0.2794)
							(mid -0.239121 -0.264521)
							(end -0.254 -0.2286)
						)
						(arc
							(start -0.254 0.2286)
							(mid -0.239121 0.264521)
							(end -0.2032 0.2794)
						)
						(arc
							(start 0.2032 0.2794)
							(mid 0.239121 0.264521)
							(end 0.254 0.2286)
						)
						(arc
							(start 0.254 -0.2286)
							(mid 0.239121 -0.264521)
							(end 0.2032 -0.2794)
						)
					)
					(width 0)
					(fill yes)
				)
			)
		)
		(pad "2" smd custom
			(at 0 0.4318 180)
			(size 0.127 0.127)
			(layers "F.Cu" "F.Mask" "F.Paste")
			(net "GND")
			(options
				(clearance outline)
				(anchor circle)
			)
			(primitives
				(gr_poly
					(pts
						(arc
							(start -0.2032 -0.2794)
							(mid -0.239121 -0.264521)
							(end -0.254 -0.2286)
						)
						(arc
							(start -0.254 0.2286)
							(mid -0.239121 0.264521)
							(end -0.2032 0.2794)
						)
						(arc
							(start 0.2032 0.2794)
							(mid 0.239121 0.264521)
							(end 0.254 0.2286)
						)
						(arc
							(start 0.254 -0.2286)
							(mid 0.239121 -0.264521)
							(end 0.2032 -0.2794)
						)
					)
					(width 0)
					(fill yes)
				)
			)
		)
	)
	(footprint ""
		(layer "F.Cu")
		(at 204.7748 -24.638 90)
		(property "Reference" "TP16"
			(at 0 0 90)
			(layer "F.SilkS")
			(hide yes)
			(effects
				(font
					(size 1.27 1.27)
				)
			)
		)
		(property "Value" "TPAD32-GP"
			(at 0 -3.166364 90)
			(unlocked yes)
			(layer "F.Fab")
			(hide yes)
			(effects
				(font
					(size 1.016 1.016)
					(thickness 0.1524)
				)
			)
		)
		(property "Device Type" "TPAD32"
			(at 0 -4.690618 90)
			(unlocked yes)
			(layer "F.Fab")
			(hide yes)
			(effects
				(font
					(size 1.016 1.016)
					(thickness 0.1524)
				)
			)
		)
		(duplicate_pad_numbers_are_jumpers no)
		(fp_poly
			(pts
				(arc
					(start 0 0.7112)
					(mid 0 -0.7112)
					(end 0 0.7112)
				)
			)
			(stroke
				(width 0)
				(type default)
			)
			(fill no)
			(layer "F.CrtYd")
		)
		(fp_poly
			(pts
				(arc
					(start 0 0.7112)
					(mid 0 -0.7112)
					(end 0 0.7112)
				)
			)
			(stroke
				(width 0)
				(type default)
			)
			(fill no)
			(layer "F.Fab")
		)
		(pad "1" smd circle
			(at 0 0 90)
			(size 0.8128 0.8128)
			(layers "F.Cu" "F.Mask" "F.Paste")
			(net "JTAG_CPU_PLD_TDO")
		)
	)
	(footprint ""
		(layer "F.Cu")
		(at 61.9252 -51.8922)
		(property "Reference" "PC113"
			(at 0 0 0)
			(layer "F.SilkS")
			(hide yes)
			(effects
				(font
					(size 1.27 1.27)
				)
			)
		)
		(property "Value" "SC22U6D3V5MX-2GP"
			(at 0 -4.9022 0)
			(unlocked yes)
			(layer "F.Fab")
			(hide yes)
			(effects
				(font
					(size 1.016 1.016)
					(thickness 0.1524)
				)
			)
		)
		(property "Device Type" "C805H58"
			(at 0 -6.8072 0)
			(unlocked yes)
			(layer "F.Fab")
			(hide yes)
			(effects
				(font
					(size 1.016 1.016)
					(thickness 0.1524)
				)
			)
		)
		(duplicate_pad_numbers_are_jumpers no)
		(fp_line
			(start 0.6096 0)
			(end -0.6096 0)
			(stroke
				(width 0.3048)
				(type default)
			)
			(layer "F.SilkS")
		)
		(fp_poly
			(pts
				(xy -0.9017 1.4351) (xy 0.9017 1.4351) (xy 0.9017 -1.4351) (xy -0.9017 -1.4351)
			)
			(stroke
				(width 0)
				(type default)
			)
			(fill no)
			(layer "F.CrtYd")
		)
		(fp_poly
			(pts
				(xy 0.9017 1.4351) (xy 0.9017 -1.4351) (xy -0.9017 -1.4351) (xy -0.9017 1.4351)
			)
			(stroke
				(width 0)
				(type default)
			)
			(fill no)
			(layer "F.Fab")
		)
		(pad "1" smd rect
			(at 0 -0.8382)
			(size 1.5494 0.9398)
			(layers "F.Cu" "F.Mask" "F.Paste")
			(net "P1V0_STBY_VOUT")
		)
		(pad "2" smd rect
			(at 0 0.8382)
			(size 1.5494 0.9398)
			(layers "F.Cu" "F.Mask" "F.Paste")
			(net "GND")
		)
	)
	(footprint ""
		(layer "F.Cu")
		(at 22.7584 -50.5206)
		(property "Reference" "PR82"
			(at 0 0 0)
			(layer "F.SilkS")
			(hide yes)
			(effects
				(font
					(size 1.27 1.27)
				)
			)
		)
		(property "Value" "0R2J-2-GP"
			(at 1.7907 -1.1176 0)
			(unlocked yes)
			(layer "F.Fab")
			(hide yes)
			(effects
				(font
					(size 1.016 1.016)
					(thickness 0.1524)
				)
			)
		)
		(property "Device Type" "R402H16"
			(at 1.7907 -2.6416 0)
			(unlocked yes)
			(layer "F.Fab")
			(hide yes)
			(effects
				(font
					(size 1.016 1.016)
					(thickness 0.1524)
				)
			)
		)
		(duplicate_pad_numbers_are_jumpers no)
		(fp_rect
			(start -0.381 0.8382)
			(end 0.381 -0.8382)
			(stroke
				(width 0)
				(type default)
			)
			(fill no)
			(layer "F.CrtYd")
		)
		(fp_rect
			(start -0.381 0.8382)
			(end 0.381 -0.8382)
			(stroke
				(width 0)
				(type default)
			)
			(fill no)
			(layer "F.Fab")
		)
		(pad "1" smd custom
			(at 0 -0.4318)
			(size 0.127 0.127)
			(layers "F.Cu" "F.Mask" "F.Paste")
			(net "VR_PVCCP_VSEN")
			(options
				(clearance outline)
				(anchor circle)
			)
			(primitives
				(gr_poly
					(pts
						(arc
							(start -0.2032 -0.2794)
							(mid -0.239121 -0.264521)
							(end -0.254 -0.2286)
						)
						(arc
							(start -0.254 0.2286)
							(mid -0.239121 0.264521)
							(end -0.2032 0.2794)
						)
						(arc
							(start 0.2032 0.2794)
							(mid 0.239121 0.264521)
							(end 0.254 0.2286)
						)
						(arc
							(start 0.254 -0.2286)
							(mid 0.239121 -0.264521)
							(end 0.2032 -0.2794)
						)
					)
					(width 0)
					(fill yes)
				)
			)
		)
		(pad "2" smd custom
			(at 0 0.4318)
			(size 0.127 0.127)
			(layers "F.Cu" "F.Mask" "F.Paste")
			(net "VR_PVCCP_VSEN_R")
			(options
				(clearance outline)
				(anchor circle)
			)
			(primitives
				(gr_poly
					(pts
						(arc
							(start -0.2032 -0.2794)
							(mid -0.239121 -0.264521)
							(end -0.254 -0.2286)
						)
						(arc
							(start -0.254 0.2286)
							(mid -0.239121 0.264521)
							(end -0.2032 0.2794)
						)
						(arc
							(start 0.2032 0.2794)
							(mid 0.239121 0.264521)
							(end 0.254 0.2286)
						)
						(arc
							(start 0.254 -0.2286)
							(mid 0.239121 -0.264521)
							(end 0.2032 -0.2794)
						)
					)
					(width 0)
					(fill yes)
				)
			)
		)
	)
	(footprint ""
		(layer "F.Cu")
		(at 33.1724 -33.0454 180)
		(property "Reference" "R472"
			(at 0 0 180)
			(layer "F.SilkS")
			(hide yes)
			(effects
				(font
					(size 1.27 1.27)
				)
			)
		)
		(property "Value" "0R2J-2-GP"
			(at 1.7907 -1.1176 180)
			(unlocked yes)
			(layer "F.Fab")
			(hide yes)
			(effects
				(font
					(size 1.016 1.016)
					(thickness 0.1524)
				)
			)
		)
		(property "Device Type" "R402H16"
			(at 1.7907 -2.6416 180)
			(unlocked yes)
			(layer "F.Fab")
			(hide yes)
			(effects
				(font
					(size 1.016 1.016)
					(thickness 0.1524)
				)
			)
		)
		(duplicate_pad_numbers_are_jumpers no)
		(fp_rect
			(start -0.381 0.8382)
			(end 0.381 -0.8382)
			(stroke
				(width 0)
				(type default)
			)
			(fill no)
			(layer "F.CrtYd")
		)
		(fp_rect
			(start -0.381 0.8382)
			(end 0.381 -0.8382)
			(stroke
				(width 0)
				(type default)
			)
			(fill no)
			(layer "F.Fab")
		)
		(pad "1" smd custom
			(at 0 -0.4318 180)
			(size 0.127 0.127)
			(layers "F.Cu" "F.Mask" "F.Paste")
			(net "XDP_CPU_R_TDO")
			(options
				(clearance outline)
				(anchor circle)
			)
			(primitives
				(gr_poly
					(pts
						(arc
							(start -0.2032 -0.2794)
							(mid -0.239121 -0.264521)
							(end -0.254 -0.2286)
						)
						(arc
							(start -0.254 0.2286)
							(mid -0.239121 0.264521)
							(end -0.2032 0.2794)
						)
						(arc
							(start 0.2032 0.2794)
							(mid 0.239121 0.264521)
							(end 0.254 0.2286)
						)
						(arc
							(start 0.254 -0.2286)
							(mid 0.239121 -0.264521)
							(end 0.2032 -0.2794)
						)
					)
					(width 0)
					(fill yes)
				)
			)
		)
		(pad "2" smd custom
			(at 0 0.4318 180)
			(size 0.127 0.127)
			(layers "F.Cu" "F.Mask" "F.Paste")
			(net "XDP_SOC_CPU_TDO")
			(options
				(clearance outline)
				(anchor circle)
			)
			(primitives
				(gr_poly
					(pts
						(arc
							(start -0.2032 -0.2794)
							(mid -0.239121 -0.264521)
							(end -0.254 -0.2286)
						)
						(arc
							(start -0.254 0.2286)
							(mid -0.239121 0.264521)
							(end -0.2032 0.2794)
						)
						(arc
							(start 0.2032 0.2794)
							(mid 0.239121 0.264521)
							(end 0.254 0.2286)
						)
						(arc
							(start 0.254 -0.2286)
							(mid 0.239121 -0.264521)
							(end 0.2032 -0.2794)
						)
					)
					(width 0)
					(fill yes)
				)
			)
		)
	)
	(footprint ""
		(layer "F.Cu")
		(at 16.3576 -63.9064 180)
		(property "Reference" "PR34"
			(at 0 0 180)
			(layer "F.SilkS")
			(hide yes)
			(effects
				(font
					(size 1.27 1.27)
				)
			)
		)
		(property "Value" "5K9R2F-GP"
			(at 1.7907 -1.1176 180)
			(unlocked yes)
			(layer "F.Fab")
			(hide yes)
			(effects
				(font
					(size 1.016 1.016)
					(thickness 0.1524)
				)
			)
		)
		(property "Device Type" "R402H16"
			(at 1.7907 -2.6416 180)
			(unlocked yes)
			(layer "F.Fab")
			(hide yes)
			(effects
				(font
					(size 1.016 1.016)
					(thickness 0.1524)
				)
			)
		)
		(duplicate_pad_numbers_are_jumpers no)
		(fp_rect
			(start -0.381 0.8382)
			(end 0.381 -0.8382)
			(stroke
				(width 0)
				(type default)
			)
			(fill no)
			(layer "F.CrtYd")
		)
		(fp_rect
			(start -0.381 0.8382)
			(end 0.381 -0.8382)
			(stroke
				(width 0)
				(type default)
			)
			(fill no)
			(layer "F.Fab")
		)
		(pad "1" smd custom
			(at 0 -0.4318 180)
			(size 0.127 0.127)
			(layers "F.Cu" "F.Mask" "F.Paste")
			(net "VR_PVNN_IMON")
			(options
				(clearance outline)
				(anchor circle)
			)
			(primitives
				(gr_poly
					(pts
						(arc
							(start -0.2032 -0.2794)
							(mid -0.239121 -0.264521)
							(end -0.254 -0.2286)
						)
						(arc
							(start -0.254 0.2286)
							(mid -0.239121 0.264521)
							(end -0.2032 0.2794)
						)
						(arc
							(start 0.2032 0.2794)
							(mid 0.239121 0.264521)
							(end 0.254 0.2286)
						)
						(arc
							(start 0.254 -0.2286)
							(mid 0.239121 -0.264521)
							(end 0.2032 -0.2794)
						)
					)
					(width 0)
					(fill yes)
				)
			)
		)
		(pad "2" smd custom
			(at 0 0.4318 180)
			(size 0.127 0.127)
			(layers "F.Cu" "F.Mask" "F.Paste")
			(net "GND")
			(options
				(clearance outline)
				(anchor circle)
			)
			(primitives
				(gr_poly
					(pts
						(arc
							(start -0.2032 -0.2794)
							(mid -0.239121 -0.264521)
							(end -0.254 -0.2286)
						)
						(arc
							(start -0.254 0.2286)
							(mid -0.239121 0.264521)
							(end -0.2032 0.2794)
						)
						(arc
							(start 0.2032 0.2794)
							(mid 0.239121 0.264521)
							(end 0.254 0.2286)
						)
						(arc
							(start 0.254 -0.2286)
							(mid 0.239121 -0.264521)
							(end 0.2032 -0.2794)
						)
					)
					(width 0)
					(fill yes)
				)
			)
		)
	)
	(footprint ""
		(layer "F.Cu")
		(at 198.12 -6.35 -90)
		(property "Reference" "R388"
			(at 0 0 270)
			(layer "F.SilkS")
			(hide yes)
			(effects
				(font
					(size 1.27 1.27)
				)
			)
		)
		(property "Value" "4K7R2F-GP"
			(at 0.064008 -3.993896 270)
			(unlocked yes)
			(layer "F.Fab")
			(hide yes)
			(effects
				(font
					(size 1.016 1.016)
					(thickness 0.1524)
				)
			)
		)
		(property "Device Type" "R402H16"
			(at 0.064008 -5.517896 270)
			(unlocked yes)
			(layer "F.Fab")
			(hide yes)
			(effects
				(font
					(size 1.016 1.016)
					(thickness 0.1524)
				)
			)
		)
		(duplicate_pad_numbers_are_jumpers no)
		(fp_rect
			(start -0.381 0.8382)
			(end 0.381 -0.8382)
			(stroke
				(width 0)
				(type default)
			)
			(fill no)
			(layer "F.CrtYd")
		)
		(fp_rect
			(start -0.381 0.8382)
			(end 0.381 -0.8382)
			(stroke
				(width 0)
				(type default)
			)
			(fill no)
			(layer "F.Fab")
		)
		(pad "1" smd custom
			(at 0 -0.4318 270)
			(size 0.127 0.127)
			(layers "F.Cu" "F.Mask" "F.Paste")
			(net "P3V3_STBY")
			(options
				(clearance outline)
				(anchor circle)
			)
			(primitives
				(gr_poly
					(pts
						(arc
							(start -0.2032 -0.2794)
							(mid -0.239121 -0.264521)
							(end -0.254 -0.2286)
						)
						(arc
							(start -0.254 0.2286)
							(mid -0.239121 0.264521)
							(end -0.2032 0.2794)
						)
						(arc
							(start 0.2032 0.2794)
							(mid 0.239121 0.264521)
							(end 0.254 0.2286)
						)
						(arc
							(start 0.254 -0.2286)
							(mid 0.239121 -0.264521)
							(end 0.2032 -0.2794)
						)
					)
					(width 0)
					(fill yes)
				)
			)
		)
		(pad "2" smd custom
			(at 0 0.4318 270)
			(size 0.127 0.127)
			(layers "F.Cu" "F.Mask" "F.Paste")
			(net "CHB_1_SA0")
			(options
				(clearance outline)
				(anchor circle)
			)
			(primitives
				(gr_poly
					(pts
						(arc
							(start -0.2032 -0.2794)
							(mid -0.239121 -0.264521)
							(end -0.254 -0.2286)
						)
						(arc
							(start -0.254 0.2286)
							(mid -0.239121 0.264521)
							(end -0.2032 0.2794)
						)
						(arc
							(start 0.2032 0.2794)
							(mid 0.239121 0.264521)
							(end 0.254 0.2286)
						)
						(arc
							(start 0.254 -0.2286)
							(mid 0.239121 -0.264521)
							(end 0.2032 -0.2794)
						)
					)
					(width 0)
					(fill yes)
				)
			)
		)
	)
	(footprint ""
		(layer "F.Cu")
		(at 74.041 -32.131 -90)
		(property "Reference" "R371"
			(at 0 0 270)
			(layer "F.SilkS")
			(hide yes)
			(effects
				(font
					(size 1.27 1.27)
				)
			)
		)
		(property "Value" "1KR2F-3-GP"
			(at 1.7907 -1.1176 270)
			(unlocked yes)
			(layer "F.Fab")
			(hide yes)
			(effects
				(font
					(size 1.016 1.016)
					(thickness 0.1524)
				)
			)
		)
		(property "Device Type" "R402H16"
			(at 1.7907 -2.6416 270)
			(unlocked yes)
			(layer "F.Fab")
			(hide yes)
			(effects
				(font
					(size 1.016 1.016)
					(thickness 0.1524)
				)
			)
		)
		(duplicate_pad_numbers_are_jumpers no)
		(fp_rect
			(start -0.381 0.8382)
			(end 0.381 -0.8382)
			(stroke
				(width 0)
				(type default)
			)
			(fill no)
			(layer "F.CrtYd")
		)
		(fp_rect
			(start -0.381 0.8382)
			(end 0.381 -0.8382)
			(stroke
				(width 0)
				(type default)
			)
			(fill no)
			(layer "F.Fab")
		)
		(pad "1" smd custom
			(at 0 -0.4318 270)
			(size 0.127 0.127)
			(layers "F.Cu" "F.Mask" "F.Paste")
			(net "GBE_WOL")
			(options
				(clearance outline)
				(anchor circle)
			)
			(primitives
				(gr_poly
					(pts
						(arc
							(start -0.2032 -0.2794)
							(mid -0.239121 -0.264521)
							(end -0.254 -0.2286)
						)
						(arc
							(start -0.254 0.2286)
							(mid -0.239121 0.264521)
							(end -0.2032 0.2794)
						)
						(arc
							(start 0.2032 0.2794)
							(mid 0.239121 0.264521)
							(end 0.254 0.2286)
						)
						(arc
							(start 0.254 -0.2286)
							(mid 0.239121 -0.264521)
							(end 0.2032 -0.2794)
						)
					)
					(width 0)
					(fill yes)
				)
			)
		)
		(pad "2" smd custom
			(at 0 0.4318 270)
			(size 0.127 0.127)
			(layers "F.Cu" "F.Mask" "F.Paste")
			(net "GND")
			(options
				(clearance outline)
				(anchor circle)
			)
			(primitives
				(gr_poly
					(pts
						(arc
							(start -0.2032 -0.2794)
							(mid -0.239121 -0.264521)
							(end -0.254 -0.2286)
						)
						(arc
							(start -0.254 0.2286)
							(mid -0.239121 0.264521)
							(end -0.2032 0.2794)
						)
						(arc
							(start 0.2032 0.2794)
							(mid 0.239121 0.264521)
							(end 0.254 0.2286)
						)
						(arc
							(start 0.254 -0.2286)
							(mid 0.239121 -0.264521)
							(end 0.2032 -0.2794)
						)
					)
					(width 0)
					(fill yes)
				)
			)
		)
	)
)
